(kicad_pcb
	(version 20260206)
	(generator "pcbnew")
	(generator_version "10.0")
	(general
		(thickness 1.6)
		(legacy_teardrops no)
	)
	(paper "A4")
	(title_block
		(title "fcb — 12433-1M.1206WZS1330.brd")
		(comment 1 "Open Vault / Knox (Wiwynn) / footprints 171-177 of 495")
	)
	(layers
		(0 "F.Cu" signal "TOP")
		(4 "In1.Cu" signal "L2GND")
		(6 "In2.Cu" signal "L3VCC")
		(2 "B.Cu" signal "BOTTOM")
		(9 "F.Adhes" user "F.Adhesive")
		(11 "B.Adhes" user "B.Adhesive")
		(13 "F.Paste" user "Package Geometry/Pastemask Top")
		(15 "B.Paste" user "Package Geometry/Pastemask Bottom")
		(5 "F.SilkS" user "Ref Des/Silkscreen Top")
		(7 "B.SilkS" user "Ref Des/Silkscreen Bottom")
		(1 "F.Mask" user "Board Geometry/Soldermask Top")
		(3 "B.Mask" user "Board Geometry/Soldermask Bottom")
		(17 "Dwgs.User" user "User.Drawings")
		(19 "Cmts.User" user "User.Comments")
		(21 "Eco1.User" user "User.Eco1")
		(23 "Eco2.User" user "User.Eco2")
		(25 "Edge.Cuts" user "Board Geometry/Outline")
		(27 "Margin" user)
		(31 "F.CrtYd" user "Package Geometry/Place Bound Top")
		(29 "B.CrtYd" user "Package Geometry/Place Bound Bottom")
		(35 "F.Fab" user "Ref Des/Assembly Top")
		(33 "B.Fab" user "Ref Des/Assembly Bottom")
	)
	(footprint ""
		(layer "F.Cu")
		(at 43.18 -400.177)
		(property "Reference" "PQ3"
			(at 0 0 0)
			(layer "F.SilkS")
			(hide yes)
			(effects
				(font
					(size 1.27 1.27)
				)
			)
		)
		(property "Value" "PH0925CL-GP"
			(at -4.2799 -0.4572 0)
			(unlocked yes)
			(layer "F.Fab")
			(hide yes)
			(effects
				(font
					(size 1.016 1.016)
					(thickness 0.1524)
				)
			)
		)
		(property "Device Type" "LFPAK-5PH48-U"
			(at -4.2799 -1.9812 0)
			(unlocked yes)
			(layer "F.Fab")
			(hide yes)
			(effects
				(font
					(size 1.016 1.016)
					(thickness 0.1524)
				)
			)
		)
		(duplicate_pad_numbers_are_jumpers no)
		(fp_line
			(start -2.7559 -6.5532)
			(end -2.7559 1.0668)
			(stroke
				(width 0.1524)
				(type default)
			)
			(layer "F.SilkS")
		)
		(fp_line
			(start -2.7559 1.0668)
			(end 2.7559 1.0668)
			(stroke
				(width 0.1524)
				(type default)
			)
			(layer "F.SilkS")
		)
		(fp_line
			(start -1.7272 1.1684)
			(end -2.1082 1.1684)
			(stroke
				(width 0.3302)
				(type default)
			)
			(layer "F.SilkS")
		)
		(fp_line
			(start 2.7559 -6.5532)
			(end -2.7559 -6.5532)
			(stroke
				(width 0.1524)
				(type default)
			)
			(layer "F.SilkS")
		)
		(fp_line
			(start 2.7559 1.0668)
			(end 2.7559 -6.5532)
			(stroke
				(width 0.1524)
				(type default)
			)
			(layer "F.SilkS")
		)
		(fp_poly
			(pts
				(xy -2.3368 1.5748) (xy -1.905 1.143) (xy -1.4732 1.5748)
			)
			(stroke
				(width 0)
				(type default)
			)
			(fill yes)
			(layer "F.SilkS")
		)
		(fp_poly
			(pts
				(xy -2.5019 -4.02971) (xy -0.3302 -4.02971) (xy -0.3302 -6.30301) (xy -2.5019 -6.30301)
			)
			(stroke
				(width 0)
				(type default)
			)
			(fill yes)
			(layer "F.Paste")
		)
		(fp_poly
			(pts
				(xy -2.5019 -1.09601) (xy -0.3302 -1.09601) (xy -0.3302 -3.36931) (xy -2.5019 -3.36931)
			)
			(stroke
				(width 0)
				(type default)
			)
			(fill yes)
			(layer "F.Paste")
		)
		(fp_poly
			(pts
				(xy 0.3302 -4.02971) (xy 2.5019 -4.02971) (xy 2.5019 -6.30301) (xy 0.3302 -6.30301)
			)
			(stroke
				(width 0)
				(type default)
			)
			(fill yes)
			(layer "F.Paste")
		)
		(fp_poly
			(pts
				(xy 0.3302 -1.09601) (xy 2.5019 -1.09601) (xy 2.5019 -3.36931) (xy 0.3302 -3.36931)
			)
			(stroke
				(width 0)
				(type default)
			)
			(fill yes)
			(layer "F.Paste")
		)
		(fp_rect
			(start -2.4511 0.3048)
			(end 2.4511 -5.6896)
			(stroke
				(width 0)
				(type default)
			)
			(fill no)
			(layer "F.CrtYd")
		)
		(fp_poly
			(pts
				(xy -3.0099 1.3208) (xy -3.0099 -6.8072) (xy 3.0099 -6.8072) (xy 3.0099 -1.016) (xy 2.4511 -1.016)
				(xy 2.4511 -5.6896) (xy -2.4511 -5.6896) (xy -2.4511 0.3048) (xy 2.4511 0.3048) (xy 2.4511 -1.0033)
				(xy 3.0099 -1.0033) (xy 3.0099 1.3208)
			)
			(stroke
				(width 0)
				(type default)
			)
			(fill no)
			(layer "F.CrtYd")
		)
		(fp_rect
			(start -3.0099 1.3208)
			(end 3.0099 -6.8072)
			(stroke
				(width 0)
				(type default)
			)
			(fill no)
			(layer "F.Fab")
		)
		(pad "1" smd rect
			(at -1.905 0)
			(size 0.762 1.6256)
			(layers "F.Cu" "F.Mask" "F.Paste")
			(net "P12V")
		)
		(pad "2" smd rect
			(at -0.635 0)
			(size 0.762 1.6256)
			(layers "F.Cu" "F.Mask" "F.Paste")
			(net "P12V")
		)
		(pad "3" smd rect
			(at 0.635 0)
			(size 0.762 1.6256)
			(layers "F.Cu" "F.Mask" "F.Paste")
			(net "P12V")
		)
		(pad "4" smd rect
			(at 1.905 0)
			(size 0.762 1.6256)
			(layers "F.Cu" "F.Mask" "F.Paste")
			(net "ADM1276_GATE_DRV3")
		)
		(pad "5" smd rect
			(at 0 -3.69951)
			(size 5.0038 5.207)
			(layers "F.Cu" "F.Mask" "F.Paste")
			(net "P12V_SENSE_TRACE")
		)
	)
	(footprint ""
		(layer "F.Cu")
		(at 31.3182 -253.8984 180)
		(property "Reference" "R47"
			(at 0 0 180)
			(layer "F.SilkS")
			(hide yes)
			(effects
				(font
					(size 1.27 1.27)
				)
			)
		)
		(property "Value" "0R2J-2-GP"
			(at 0.064008 -3.993896 180)
			(unlocked yes)
			(layer "F.Fab")
			(hide yes)
			(effects
				(font
					(size 1.016 1.016)
					(thickness 0.1524)
				)
			)
		)
		(property "Device Type" "R402H16"
			(at 0.064008 -5.517896 180)
			(unlocked yes)
			(layer "F.Fab")
			(hide yes)
			(effects
				(font
					(size 1.016 1.016)
					(thickness 0.1524)
				)
			)
		)
		(duplicate_pad_numbers_are_jumpers no)
		(fp_line
			(start 0.508 -0.9398)
			(end -0.508 -0.9398)
			(stroke
				(width 0.1524)
				(type default)
			)
			(layer "F.SilkS")
		)
		(fp_line
			(start -0.508 -0.9398)
			(end -0.508 0.9398)
			(stroke
				(width 0.1524)
				(type default)
			)
			(layer "F.SilkS")
		)
		(fp_rect
			(start -0.508 0.9398)
			(end 0.508 -0.9398)
			(stroke
				(width 0)
				(type default)
			)
			(fill no)
			(layer "F.CrtYd")
		)
		(fp_rect
			(start -0.508 0.9398)
			(end 0.508 -0.9398)
			(stroke
				(width 0)
				(type default)
			)
			(fill no)
			(layer "F.Fab")
		)
		(pad "1" smd custom
			(at 0 -0.4445 180)
			(size 0.1397 0.1397)
			(layers "F.Cu" "F.Mask" "F.Paste")
			(net "I2C_C_SDA_EEPROM")
			(options
				(clearance outline)
				(anchor circle)
			)
			(primitives
				(gr_poly
					(pts
						(arc
							(start -0.1778 -0.2794)
							(mid -0.249642 -0.249642)
							(end -0.2794 -0.1778)
						)
						(arc
							(start -0.2794 0.1778)
							(mid -0.249642 0.249642)
							(end -0.1778 0.2794)
						)
						(arc
							(start 0.1778 0.2794)
							(mid 0.249642 0.249642)
							(end 0.2794 0.1778)
						)
						(arc
							(start 0.2794 -0.1778)
							(mid 0.249642 -0.249642)
							(end 0.1778 -0.2794)
						)
					)
					(width 0)
					(fill yes)
				)
			)
		)
		(pad "2" smd custom
			(at 0 0.4445 180)
			(size 0.1397 0.1397)
			(layers "F.Cu" "F.Mask" "F.Paste")
			(net "I2C_C_SDA")
			(options
				(clearance outline)
				(anchor circle)
			)
			(primitives
				(gr_poly
					(pts
						(arc
							(start -0.1778 -0.2794)
							(mid -0.249642 -0.249642)
							(end -0.2794 -0.1778)
						)
						(arc
							(start -0.2794 0.1778)
							(mid -0.249642 0.249642)
							(end -0.1778 0.2794)
						)
						(arc
							(start 0.1778 0.2794)
							(mid 0.249642 0.249642)
							(end 0.2794 0.1778)
						)
						(arc
							(start 0.2794 -0.1778)
							(mid 0.249642 -0.249642)
							(end 0.1778 -0.2794)
						)
					)
					(width 0)
					(fill yes)
				)
			)
		)
	)
	(footprint ""
		(layer "F.Cu")
		(at 21.766784 -216.6366 90)
		(property "Reference" "R132"
			(at 0 0 90)
			(layer "F.SilkS")
			(hide yes)
			(effects
				(font
					(size 1.27 1.27)
				)
			)
		)
		(property "Value" "4K7R2F-GP"
			(at 0.064008 -3.993896 90)
			(unlocked yes)
			(layer "F.Fab")
			(hide yes)
			(effects
				(font
					(size 1.016 1.016)
					(thickness 0.1524)
				)
			)
		)
		(property "Device Type" "R402H16"
			(at 0.064008 -5.517896 90)
			(unlocked yes)
			(layer "F.Fab")
			(hide yes)
			(effects
				(font
					(size 1.016 1.016)
					(thickness 0.1524)
				)
			)
		)
		(duplicate_pad_numbers_are_jumpers no)
		(fp_line
			(start 0.508 -0.9398)
			(end -0.508 -0.9398)
			(stroke
				(width 0.1524)
				(type default)
			)
			(layer "F.SilkS")
		)
		(fp_line
			(start -0.508 -0.9398)
			(end -0.508 0.9398)
			(stroke
				(width 0.1524)
				(type default)
			)
			(layer "F.SilkS")
		)
		(fp_rect
			(start -0.508 0.9398)
			(end 0.508 -0.9398)
			(stroke
				(width 0)
				(type default)
			)
			(fill no)
			(layer "F.CrtYd")
		)
		(fp_rect
			(start -0.508 0.9398)
			(end 0.508 -0.9398)
			(stroke
				(width 0)
				(type default)
			)
			(fill no)
			(layer "F.Fab")
		)
		(pad "1" smd custom
			(at 0 -0.4445 90)
			(size 0.1397 0.1397)
			(layers "F.Cu" "F.Mask" "F.Paste")
			(net "P3V3")
			(options
				(clearance outline)
				(anchor circle)
			)
			(primitives
				(gr_poly
					(pts
						(arc
							(start -0.1778 -0.2794)
							(mid -0.249642 -0.249642)
							(end -0.2794 -0.1778)
						)
						(arc
							(start -0.2794 0.1778)
							(mid -0.249642 0.249642)
							(end -0.1778 0.2794)
						)
						(arc
							(start 0.1778 0.2794)
							(mid 0.249642 0.249642)
							(end 0.2794 0.1778)
						)
						(arc
							(start 0.2794 -0.1778)
							(mid 0.249642 -0.249642)
							(end 0.1778 -0.2794)
						)
					)
					(width 0)
					(fill yes)
				)
			)
		)
		(pad "2" smd custom
			(at 0 0.4445 90)
			(size 0.1397 0.1397)
			(layers "F.Cu" "F.Mask" "F.Paste")
			(net "PWM_OUT_FAN4")
			(options
				(clearance outline)
				(anchor circle)
			)
			(primitives
				(gr_poly
					(pts
						(arc
							(start -0.1778 -0.2794)
							(mid -0.249642 -0.249642)
							(end -0.2794 -0.1778)
						)
						(arc
							(start -0.2794 0.1778)
							(mid -0.249642 0.249642)
							(end -0.1778 0.2794)
						)
						(arc
							(start 0.1778 0.2794)
							(mid 0.249642 0.249642)
							(end 0.2794 0.1778)
						)
						(arc
							(start 0.2794 -0.1778)
							(mid 0.249642 -0.249642)
							(end 0.1778 -0.2794)
						)
					)
					(width 0)
					(fill yes)
				)
			)
		)
	)
	(footprint ""
		(layer "F.Cu")
		(at 37.465 -366.014 180)
		(property "Reference" "PQ4"
			(at 0 0 180)
			(layer "F.SilkS")
			(hide yes)
			(effects
				(font
					(size 1.27 1.27)
				)
			)
		)
		(property "Value" "MMBT3906-3-GP"
			(at 0.10287 -10.29843 180)
			(unlocked yes)
			(layer "F.Fab")
			(hide yes)
			(effects
				(font
					(size 1.016 1.016)
					(thickness 0.1524)
				)
			)
		)
		(property "Device Type" "SOT23CBE2D4H44"
			(at 0.10287 -12.20343 180)
			(unlocked yes)
			(layer "F.Fab")
			(hide yes)
			(effects
				(font
					(size 1.016 1.016)
					(thickness 0.1524)
				)
			)
		)
		(duplicate_pad_numbers_are_jumpers no)
		(fp_line
			(start 1.651 1.778)
			(end 1.651 -1.778)
			(stroke
				(width 0.1524)
				(type default)
			)
			(layer "F.SilkS")
		)
		(fp_line
			(start 1.651 -1.778)
			(end -1.651 -1.778)
			(stroke
				(width 0.1524)
				(type default)
			)
			(layer "F.SilkS")
		)
		(fp_line
			(start -1.651 1.778)
			(end 1.651 1.778)
			(stroke
				(width 0.1524)
				(type default)
			)
			(layer "F.SilkS")
		)
		(fp_line
			(start -1.651 -1.778)
			(end -1.651 1.778)
			(stroke
				(width 0.1524)
				(type default)
			)
			(layer "F.SilkS")
		)
		(fp_poly
			(pts
				(xy -1.778 1.8796) (xy -1.778 -1.8796) (xy 1.778 -1.8796) (xy 1.778 1.8796)
			)
			(stroke
				(width 0)
				(type default)
			)
			(fill no)
			(layer "F.CrtYd")
		)
		(fp_poly
			(pts
				(xy -1.778 1.8796) (xy -1.778 -1.8796) (xy 1.778 -1.8796) (xy 1.778 1.8796)
			)
			(stroke
				(width 0)
				(type default)
			)
			(fill no)
			(layer "F.Fab")
		)
		(pad "B" smd custom
			(at -0.98425 0.9525 180)
			(size 0.1905 0.1905)
			(layers "F.Cu" "F.Mask" "F.Paste")
			(net "ADM1276_LATCH_B")
			(options
				(clearance outline)
				(anchor circle)
			)
			(primitives
				(gr_poly
					(pts
						(arc
							(start -0.1778 0.5715)
							(mid -0.321484 0.511984)
							(end -0.381 0.3683)
						)
						(arc
							(start -0.381 -0.3683)
							(mid -0.321484 -0.511984)
							(end -0.1778 -0.5715)
						)
						(arc
							(start 0.1778 -0.5715)
							(mid 0.321484 -0.511984)
							(end 0.381 -0.3683)
						)
						(arc
							(start 0.381 0.3683)
							(mid 0.321484 0.511984)
							(end 0.1778 0.5715)
						)
					)
					(width 0)
					(fill yes)
				)
			)
		)
		(pad "C" smd custom
			(at 0 -0.9525 180)
			(size 0.1905 0.1905)
			(layers "F.Cu" "F.Mask" "F.Paste")
			(net "TEMP_ALM#_REVERSE_R")
			(options
				(clearance outline)
				(anchor circle)
			)
			(primitives
				(gr_poly
					(pts
						(arc
							(start -0.1778 0.5715)
							(mid -0.321484 0.511984)
							(end -0.381 0.3683)
						)
						(arc
							(start -0.381 -0.3683)
							(mid -0.321484 -0.511984)
							(end -0.1778 -0.5715)
						)
						(arc
							(start 0.1778 -0.5715)
							(mid 0.321484 -0.511984)
							(end 0.381 -0.3683)
						)
						(arc
							(start 0.381 0.3683)
							(mid 0.321484 0.511984)
							(end 0.1778 0.5715)
						)
					)
					(width 0)
					(fill yes)
				)
			)
		)
		(pad "E" smd custom
			(at 0.98425 0.9525 180)
			(size 0.1905 0.1905)
			(layers "F.Cu" "F.Mask" "F.Paste")
			(net "ADM1276_EN_NET")
			(options
				(clearance outline)
				(anchor circle)
			)
			(primitives
				(gr_poly
					(pts
						(arc
							(start -0.1778 0.5715)
							(mid -0.321484 0.511984)
							(end -0.381 0.3683)
						)
						(arc
							(start -0.381 -0.3683)
							(mid -0.321484 -0.511984)
							(end -0.1778 -0.5715)
						)
						(arc
							(start 0.1778 -0.5715)
							(mid 0.321484 -0.511984)
							(end 0.381 -0.3683)
						)
						(arc
							(start 0.381 0.3683)
							(mid 0.321484 0.511984)
							(end 0.1778 0.5715)
						)
					)
					(width 0)
					(fill yes)
				)
			)
		)
	)
	(footprint ""
		(layer "F.Cu")
		(at 13.5636 -64.2112 -90)
		(property "Reference" "C56"
			(at 0 0 270)
			(layer "F.SilkS")
			(hide yes)
			(effects
				(font
					(size 1.27 1.27)
				)
			)
		)
		(property "Value" "SC220P50V3JN-GP"
			(at 0 -2.8194 270)
			(unlocked yes)
			(layer "F.Fab")
			(hide yes)
			(effects
				(font
					(size 1.016 1.016)
					(thickness 0.1524)
				)
			)
		)
		(property "Device Type" "C603H36"
			(at 0 -4.3434 270)
			(unlocked yes)
			(layer "F.Fab")
			(hide yes)
			(effects
				(font
					(size 1.016 1.016)
					(thickness 0.1524)
				)
			)
		)
		(duplicate_pad_numbers_are_jumpers no)
		(fp_line
			(start 0.508 0)
			(end -0.508 0)
			(stroke
				(width 0.2032)
				(type default)
			)
			(layer "F.SilkS")
		)
		(fp_rect
			(start -0.5842 1.3335)
			(end 0.5842 -1.3335)
			(stroke
				(width 0)
				(type default)
			)
			(fill no)
			(layer "F.CrtYd")
		)
		(fp_rect
			(start -0.5842 1.3335)
			(end 0.5842 -1.3335)
			(stroke
				(width 0)
				(type default)
			)
			(fill no)
			(layer "F.Fab")
		)
		(pad "1" smd custom
			(at 0 -0.762 270)
			(size 0.2159 0.2159)
			(layers "F.Cu" "F.Mask" "F.Paste")
			(net "I2C_C_SCL_CONN_R")
			(options
				(clearance outline)
				(anchor circle)
			)
			(primitives
				(gr_poly
					(pts
						(arc
							(start -0.3302 -0.4318)
							(mid -0.402042 -0.402042)
							(end -0.4318 -0.3302)
						)
						(arc
							(start -0.4318 0.3302)
							(mid -0.402042 0.402042)
							(end -0.3302 0.4318)
						)
						(arc
							(start 0.3302 0.4318)
							(mid 0.402042 0.402042)
							(end 0.4318 0.3302)
						)
						(arc
							(start 0.4318 -0.3302)
							(mid 0.402042 -0.402042)
							(end 0.3302 -0.4318)
						)
					)
					(width 0)
					(fill yes)
				)
			)
		)
		(pad "2" smd custom
			(at 0 0.762 270)
			(size 0.2159 0.2159)
			(layers "F.Cu" "F.Mask" "F.Paste")
			(net "GND")
			(options
				(clearance outline)
				(anchor circle)
			)
			(primitives
				(gr_poly
					(pts
						(arc
							(start -0.3302 -0.4318)
							(mid -0.402042 -0.402042)
							(end -0.4318 -0.3302)
						)
						(arc
							(start -0.4318 0.3302)
							(mid -0.402042 0.402042)
							(end -0.3302 0.4318)
						)
						(arc
							(start 0.3302 0.4318)
							(mid 0.402042 0.402042)
							(end 0.4318 0.3302)
						)
						(arc
							(start 0.4318 -0.3302)
							(mid 0.402042 -0.402042)
							(end 0.3302 -0.4318)
						)
					)
					(width 0)
					(fill yes)
				)
			)
		)
	)
	(footprint ""
		(layer "F.Cu")
		(at 18.7706 -139.7254 90)
		(property "Reference" "TP23"
			(at 0 0 90)
			(layer "F.SilkS")
			(hide yes)
			(effects
				(font
					(size 1.27 1.27)
				)
			)
		)
		(property "Value" "TPAD32-GP"
			(at 0 -3.166364 90)
			(unlocked yes)
			(layer "F.Fab")
			(hide yes)
			(effects
				(font
					(size 1.016 1.016)
					(thickness 0.1524)
				)
			)
		)
		(property "Device Type" "TPAD32"
			(at 0 -4.690618 90)
			(unlocked yes)
			(layer "F.Fab")
			(hide yes)
			(effects
				(font
					(size 1.016 1.016)
					(thickness 0.1524)
				)
			)
		)
		(duplicate_pad_numbers_are_jumpers no)
		(fp_poly
			(pts
				(arc
					(start 0.7112 0)
					(mid -0.7112 0)
					(end 0.7112 0)
				)
			)
			(stroke
				(width 0)
				(type default)
			)
			(fill no)
			(layer "F.CrtYd")
		)
		(fp_poly
			(pts
				(arc
					(start 0.7112 0)
					(mid -0.7112 0)
					(end 0.7112 0)
				)
			)
			(stroke
				(width 0)
				(type default)
			)
			(fill no)
			(layer "F.Fab")
		)
		(pad "1" smd circle
			(at 0 0 90)
			(size 0.8128 0.8128)
			(layers "F.Cu" "F.Mask" "F.Paste")
			(net "P12VU_2490_PG")
		)
	)
	(footprint ""
		(layer "F.Cu")
		(at 24.2824 -361.188 180)
		(property "Reference" "PR11"
			(at 0 0 180)
			(layer "F.SilkS")
			(hide yes)
			(effects
				(font
					(size 1.27 1.27)
				)
			)
		)
		(property "Value" "150KR2F-L-GP"
			(at 0.064008 -3.993896 180)
			(unlocked yes)
			(layer "F.Fab")
			(hide yes)
			(effects
				(font
					(size 1.016 1.016)
					(thickness 0.1524)
				)
			)
		)
		(property "Device Type" "R402H16"
			(at 0.064008 -5.517896 180)
			(unlocked yes)
			(layer "F.Fab")
			(hide yes)
			(effects
				(font
					(size 1.016 1.016)
					(thickness 0.1524)
				)
			)
		)
		(duplicate_pad_numbers_are_jumpers no)
		(fp_line
			(start 0.508 -0.9398)
			(end -0.508 -0.9398)
			(stroke
				(width 0.1524)
				(type default)
			)
			(layer "F.SilkS")
		)
		(fp_line
			(start -0.508 -0.9398)
			(end -0.508 0.9398)
			(stroke
				(width 0.1524)
				(type default)
			)
			(layer "F.SilkS")
		)
		(fp_rect
			(start -0.508 0.9398)
			(end 0.508 -0.9398)
			(stroke
				(width 0)
				(type default)
			)
			(fill no)
			(layer "F.CrtYd")
		)
		(fp_rect
			(start -0.508 0.9398)
			(end 0.508 -0.9398)
			(stroke
				(width 0)
				(type default)
			)
			(fill no)
			(layer "F.Fab")
		)
		(pad "1" smd custom
			(at 0 -0.4445 180)
			(size 0.1397 0.1397)
			(layers "F.Cu" "F.Mask" "F.Paste")
			(net "ADM1276_ADR")
			(options
				(clearance outline)
				(anchor circle)
			)
			(primitives
				(gr_poly
					(pts
						(arc
							(start -0.1778 -0.2794)
							(mid -0.249642 -0.249642)
							(end -0.2794 -0.1778)
						)
						(arc
							(start -0.2794 0.1778)
							(mid -0.249642 0.249642)
							(end -0.1778 0.2794)
						)
						(arc
							(start 0.1778 0.2794)
							(mid 0.249642 0.249642)
							(end 0.2794 0.1778)
						)
						(arc
							(start 0.2794 -0.1778)
							(mid 0.249642 -0.249642)
							(end 0.1778 -0.2794)
						)
					)
					(width 0)
					(fill yes)
				)
			)
		)
		(pad "2" smd custom
			(at 0 0.4445 180)
			(size 0.1397 0.1397)
			(layers "F.Cu" "F.Mask" "F.Paste")
			(net "GND")
			(options
				(clearance outline)
				(anchor circle)
			)
			(primitives
				(gr_poly
					(pts
						(arc
							(start -0.1778 -0.2794)
							(mid -0.249642 -0.249642)
							(end -0.2794 -0.1778)
						)
						(arc
							(start -0.2794 0.1778)
							(mid -0.249642 0.249642)
							(end -0.1778 0.2794)
						)
						(arc
							(start 0.1778 0.2794)
							(mid 0.249642 0.249642)
							(end 0.2794 0.1778)
						)
						(arc
							(start 0.2794 -0.1778)
							(mid 0.249642 -0.249642)
							(end 0.1778 -0.2794)
						)
					)
					(width 0)
					(fill yes)
				)
			)
		)
	)
)
